(kicad_pcb
	(version 20241229)
	(generator "pcbnew")
	(generator_version "9.0")
	(general
		(thickness 1.61)
		(legacy_teardrops no)
	)
	(paper "A3")
	(title_block
		(title "RDIMM DDR5 Tester")
		(date "2026-05-21")
		(rev "2.2.0")
		(company "Antmicro")
		(comment 9 "footprints 717-721 of 796")
	)
	(layers
		(0 "F.Cu" signal)
		(4 "In1.Cu" power)
		(6 "In2.Cu" mixed)
		(8 "In3.Cu" power)
		(10 "In4.Cu" mixed)
		(12 "In5.Cu" power)
		(14 "In6.Cu" mixed)
		(16 "In7.Cu" power)
		(18 "In8.Cu" power)
		(20 "In9.Cu" mixed)
		(22 "In10.Cu" power)
		(2 "B.Cu" signal)
		(9 "F.Adhes" user "F.Adhesive")
		(11 "B.Adhes" user "B.Adhesive")
		(13 "F.Paste" user)
		(15 "B.Paste" user)
		(5 "F.SilkS" user "F.Silkscreen")
		(7 "B.SilkS" user "B.Silkscreen")
		(1 "F.Mask" user)
		(3 "B.Mask" user)
		(17 "Dwgs.User" user "User.Drawings")
		(19 "Cmts.User" user "User.Comments")
		(21 "Eco1.User" user "User.Eco1")
		(23 "Eco2.User" user "User.Eco2")
		(25 "Edge.Cuts" user)
		(27 "Margin" user)
		(31 "F.CrtYd" user "F.Courtyard")
		(29 "B.CrtYd" user "B.Courtyard")
		(35 "F.Fab" user)
		(33 "B.Fab" user)
	)
	(footprint "antmicro-footprints:SOT-323"
		(layer "B.Cu")
		(at 252.15 183.499)
		(property "Reference" "Q24"
			(at -1.05 -1.7 0)
			(layer "B.SilkS")
			(effects
				(font
					(size 0.7 0.7)
					(thickness 0.15)
				)
				(justify right bottom mirror)
			)
		)
		(property "Value" "BSS84AKW"
			(at 0 -2.749 0)
			(layer "B.Fab")
			(effects
				(font
					(size 0.7 0.7)
					(thickness 0.15)
				)
				(justify right bottom mirror)
			)
		)
		(property "Datasheet" "https://assets.nexperia.com/documents/data-sheet/BSS84AKW.pdf"
			(at 0 0 0)
			(layer "F.Fab")
			(hide yes)
			(effects
				(font
					(size 1.27 1.27)
					(thickness 0.15)
				)
			)
		)
		(property "MPN" "BSS84AKW,115"
			(at 0 0 0)
			(unlocked yes)
			(layer "B.Fab")
			(hide yes)
			(effects
				(font
					(size 1 1)
					(thickness 0.15)
				)
				(justify mirror)
			)
		)
		(property "Manufacturer" "Nexperia"
			(at 0 0 0)
			(unlocked yes)
			(layer "B.Fab")
			(hide yes)
			(effects
				(font
					(size 1 1)
					(thickness 0.15)
				)
				(justify mirror)
			)
		)
		(property "Author" "Antmicro"
			(at 0 0 0)
			(unlocked yes)
			(layer "B.Fab")
			(hide yes)
			(effects
				(font
					(size 1 1)
					(thickness 0.15)
				)
				(justify mirror)
			)
		)
		(property "License" "Apache-2.0"
			(at 0 0 0)
			(unlocked yes)
			(layer "B.Fab")
			(hide yes)
			(effects
				(font
					(size 1 1)
					(thickness 0.15)
				)
				(justify mirror)
			)
		)
		(sheetname "/I^{2}C + I3C/")
		(sheetfile "i2c.kicad_sch")
		(attr smd)
		(fp_line
			(start -0.802 -1.199)
			(end -0.5 -1.199)
			(stroke
				(width 0.15)
				(type solid)
			)
			(layer "B.SilkS")
		)
		(fp_line
			(start -0.802 -1.05)
			(end -0.802 -1.199)
			(stroke
				(width 0.15)
				(type solid)
			)
			(layer "B.SilkS")
		)
		(fp_line
			(start -0.802 1.2)
			(end -0.802 1.05)
			(stroke
				(width 0.15)
				(type solid)
			)
			(layer "B.SilkS")
		)
		(fp_line
			(start -0.402 1.2)
			(end -0.802 1.2)
			(stroke
				(width 0.15)
				(type solid)
			)
			(layer "B.SilkS")
		)
		(fp_line
			(start 0.498 -1.199)
			(end 0.8 -1.199)
			(stroke
				(width 0.15)
				(type solid)
			)
			(layer "B.SilkS")
		)
		(fp_line
			(start 0.498 1.2)
			(end 0.8 1.2)
			(stroke
				(width 0.15)
				(type solid)
			)
			(layer "B.SilkS")
		)
		(fp_line
			(start 0.8 -1.199)
			(end 0.8 -0.9)
			(stroke
				(width 0.15)
				(type solid)
			)
			(layer "B.SilkS")
		)
		(fp_line
			(start 0.8 1.2)
			(end 0.8 0.902)
			(stroke
				(width 0.15)
				(type solid)
			)
			(layer "B.SilkS")
		)
		(fp_circle
			(center -1.05 1.156824)
			(end -1 1.129824)
			(stroke
				(width 0.15)
				(type solid)
			)
			(fill no)
			(layer "B.SilkS")
		)
		(fp_rect
			(start -1.35 1.35)
			(end 1.35 -1.35)
			(stroke
				(width 0.05)
				(type solid)
			)
			(fill no)
			(layer "B.CrtYd")
		)
		(fp_line
			(start -0.677 -1.1)
			(end 0.675 -1.1)
			(stroke
				(width 0.15)
				(type solid)
			)
			(layer "B.Fab")
		)
		(fp_line
			(start -0.677 1.101)
			(end -0.677 -1.1)
			(stroke
				(width 0.15)
				(type solid)
			)
			(layer "B.Fab")
		)
		(fp_line
			(start -0.677 1.101)
			(end 0.675 1.101)
			(stroke
				(width 0.15)
				(type solid)
			)
			(layer "B.Fab")
		)
		(fp_line
			(start 0.675 1.101)
			(end 0.675 -1.1)
			(stroke
				(width 0.15)
				(type solid)
			)
			(layer "B.Fab")
		)
		(fp_text user "${REFERENCE}"
			(at -1.35 -4.749 180)
			(layer "B.Fab")
			(effects
				(font
					(size 0.7 0.7)
					(thickness 0.15)
				)
				(justify left bottom mirror)
			)
		)
		(fp_text user "License: Apache-2.0"
			(at -1.35 -5.949 180)
			(layer "B.Fab")
			(effects
				(font
					(size 0.7 0.7)
					(thickness 0.15)
				)
				(justify left bottom mirror)
			)
		)
		(fp_text user "Author: Antmicro"
			(at -1.35 -7.149 180)
			(layer "B.Fab")
			(effects
				(font
					(size 0.7 0.7)
					(thickness 0.15)
				)
				(justify left bottom mirror)
			)
		)
		(pad "1" smd rect
			(at -0.927 0.652)
			(size 0.55 0.6)
			(layers "B.Cu" "B.Mask" "B.Paste")
			(net 779 "~{I3C_EXT_PU}")
			(pinfunction "G")
			(pintype "bidirectional")
		)
		(pad "2" smd rect
			(at -0.927 -0.65)
			(size 0.55 0.6)
			(layers "B.Cu" "B.Mask" "B.Paste")
			(net 775 "Net-(Q24-S)")
			(pinfunction "S")
			(pintype "bidirectional")
		)
		(pad "3" smd rect
			(at 0.925 0)
			(size 0.55 0.6)
			(layers "B.Cu" "B.Mask" "B.Paste")
			(net 782 "Net-(Q24-D)")
			(pinfunction "D")
			(pintype "bidirectional")
		)
	)
	(footprint "antmicro-footprints:R_0402_1005Metric"
		(layer "B.Cu")
		(at 238.424499 187.849 180)
		(descr "Resistor SMD 0402")
		(tags "resistor SMD 0402")
		(property "Reference" "R176"
			(at -3.95 -0.5 0)
			(layer "B.SilkS")
			(effects
				(font
					(size 0.7 0.7)
					(thickness 0.15)
				)
				(justify left bottom mirror)
			)
		)
		(property "Value" "R_0R_0402"
			(at -1.011843 -1.772047 0)
			(layer "B.Fab")
			(effects
				(font
					(size 0.7 0.7)
					(thickness 0.15)
				)
				(justify left bottom mirror)
			)
		)
		(property "Datasheet" "https://industrial.panasonic.com/cdbs/www-data/pdf/RDA0000/AOA0000C301.pdf"
			(at 0 0 180)
			(layer "F.Fab")
			(hide yes)
			(effects
				(font
					(size 1.27 1.27)
					(thickness 0.15)
				)
			)
		)
		(property "Manufacturer" "Panasonic"
			(at 0 0 180)
			(unlocked yes)
			(layer "B.Fab")
			(hide yes)
			(effects
				(font
					(size 1 1)
					(thickness 0.15)
				)
				(justify mirror)
			)
		)
		(property "MPN" "ERJ2GE0R00X"
			(at 0 0 180)
			(unlocked yes)
			(layer "B.Fab")
			(hide yes)
			(effects
				(font
					(size 1 1)
					(thickness 0.15)
				)
				(justify mirror)
			)
		)
		(property "Val" "0R"
			(at 0 0 180)
			(unlocked yes)
			(layer "B.Fab")
			(hide yes)
			(effects
				(font
					(size 1 1)
					(thickness 0.15)
				)
				(justify mirror)
			)
		)
		(property "License" "Apache-2.0"
			(at 0 0 180)
			(unlocked yes)
			(layer "B.Fab")
			(hide yes)
			(effects
				(font
					(size 1 1)
					(thickness 0.15)
				)
				(justify mirror)
			)
		)
		(property "Author" "Antmicro"
			(at 0 0 180)
			(unlocked yes)
			(layer "B.Fab")
			(hide yes)
			(effects
				(font
					(size 1 1)
					(thickness 0.15)
				)
				(justify mirror)
			)
		)
		(property "Tolerance" "~"
			(at 0 0 180)
			(unlocked yes)
			(layer "B.Fab")
			(hide yes)
			(effects
				(font
					(size 1 1)
					(thickness 0.15)
				)
				(justify mirror)
			)
		)
		(property "Current" "1A"
			(at 0 0 180)
			(unlocked yes)
			(layer "B.Fab")
			(hide yes)
			(effects
				(font
					(size 1 1)
					(thickness 0.15)
				)
				(justify mirror)
			)
		)
		(sheetname "/I^{2}C + I3C/")
		(sheetfile "i2c.kicad_sch")
		(attr smd exclude_from_bom dnp)
		(fp_rect
			(start -0.925 0.47)
			(end 0.925 -0.47)
			(stroke
				(width 0.05)
				(type default)
			)
			(fill no)
			(layer "B.CrtYd")
		)
		(fp_rect
			(start -0.5 0.25)
			(end 0.5 -0.25)
			(stroke
				(width 0.15)
				(type solid)
			)
			(fill no)
			(layer "B.Fab")
		)
		(fp_text user "License: Apache-2.0"
			(at -0.95 -5.169 0)
			(layer "B.Fab")
			(effects
				(font
					(size 0.7 0.7)
					(thickness 0.15)
				)
				(justify left bottom mirror)
			)
		)
		(fp_text user "Author: Antmicro"
			(at -0.95 -4.169 0)
			(layer "B.Fab")
			(effects
				(font
					(size 0.7 0.7)
					(thickness 0.15)
				)
				(justify left bottom mirror)
			)
		)
		(fp_text user "${REFERENCE}"
			(at -0.95 -3.168 0)
			(layer "B.Fab")
			(effects
				(font
					(size 0.7 0.7)
					(thickness 0.15)
				)
				(justify left bottom mirror)
			)
		)
		(pad "1" smd roundrect
			(at -0.48 0 180)
			(size 0.59 0.64)
			(layers "B.Cu" "B.Mask" "B.Paste")
			(roundrect_rratio 0.25)
			(net 533 "/I^{2}C + I3C/PWR.SDA")
			(pintype "passive")
		)
		(pad "2" smd roundrect
			(at 0.48 0 180)
			(size 0.59 0.64)
			(layers "B.Cu" "B.Mask" "B.Paste")
			(roundrect_rratio 0.25)
			(net 527 "/Debug FTDI + VNA/FTDI.SDA")
			(pintype "passive")
		)
	)
	(footprint "antmicro-footprints:R_0402_1005Metric"
		(layer "B.Cu")
		(at 203.25 136.0045)
		(descr "Resistor SMD 0402")
		(tags "resistor SMD 0402")
		(property "Reference" "R254"
			(at -2.35 0 0)
			(layer "B.SilkS")
			(effects
				(font
					(size 0.7 0.7)
					(thickness 0.15)
				)
				(justify mirror)
			)
		)
		(property "Value" "R_1k_0402"
			(at -1.011843 -1.772047 0)
			(layer "B.Fab")
			(effects
				(font
					(size 0.7 0.7)
					(thickness 0.15)
				)
				(justify right top mirror)
			)
		)
		(property "Datasheet" "https://www.bourns.com/docs/product-datasheets/cr.pdf"
			(at 0 0 0)
			(layer "B.Fab")
			(hide yes)
			(effects
				(font
					(size 1.27 1.27)
					(thickness 0.15)
				)
				(justify mirror)
			)
		)
		(property "MPN" "CR0402-FX-1001GLF"
			(at 0 0 180)
			(unlocked yes)
			(layer "B.Fab")
			(hide yes)
			(effects
				(font
					(size 1 1)
					(thickness 0.15)
				)
				(justify mirror)
			)
		)
		(property "Manufacturer" "Bourns"
			(at 0 0 180)
			(unlocked yes)
			(layer "B.Fab")
			(hide yes)
			(effects
				(font
					(size 1 1)
					(thickness 0.15)
				)
				(justify mirror)
			)
		)
		(property "License" "Apache-2.0"
			(at 0 0 180)
			(unlocked yes)
			(layer "B.Fab")
			(hide yes)
			(effects
				(font
					(size 1 1)
					(thickness 0.15)
				)
				(justify mirror)
			)
		)
		(property "Author" "Antmicro"
			(at 0 0 180)
			(unlocked yes)
			(layer "B.Fab")
			(hide yes)
			(effects
				(font
					(size 1 1)
					(thickness 0.15)
				)
				(justify mirror)
			)
		)
		(property "Val" "1k"
			(at 0 0 180)
			(unlocked yes)
			(layer "B.Fab")
			(hide yes)
			(effects
				(font
					(size 1 1)
					(thickness 0.15)
				)
				(justify mirror)
			)
		)
		(property "Tolerance" "1%"
			(at 0 0 180)
			(unlocked yes)
			(layer "B.Fab")
			(hide yes)
			(effects
				(font
					(size 1 1)
					(thickness 0.15)
				)
				(justify mirror)
			)
		)
		(sheetname "/FPGA banks HP/")
		(sheetfile "fpga-hp-banks.kicad_sch")
		(attr smd)
		(fp_rect
			(start -0.925 0.47)
			(end 0.925 -0.47)
			(stroke
				(width 0.05)
				(type default)
			)
			(fill no)
			(layer "B.CrtYd")
		)
		(fp_rect
			(start -0.5 0.25)
			(end 0.5 -0.25)
			(stroke
				(width 0.15)
				(type solid)
			)
			(fill no)
			(layer "B.Fab")
		)
		(fp_text user "${REFERENCE}"
			(at -0.95 -3.168 0)
			(layer "B.Fab")
			(effects
				(font
					(size 0.7 0.7)
					(thickness 0.15)
				)
				(justify right top mirror)
			)
		)
		(fp_text user "License: Apache-2.0"
			(at -0.95 -5.169 0)
			(layer "B.Fab")
			(effects
				(font
					(size 0.7 0.7)
					(thickness 0.15)
				)
				(justify right top mirror)
			)
		)
		(fp_text user "Author: Antmicro"
			(at -0.95 -4.169 0)
			(layer "B.Fab")
			(effects
				(font
					(size 0.7 0.7)
					(thickness 0.15)
				)
				(justify right top mirror)
			)
		)
		(pad "1" smd roundrect
			(at -0.48 0)
			(size 0.59 0.64)
			(layers "B.Cu" "B.Mask" "B.Paste")
			(roundrect_rratio 0.25)
			(net 1 "GND")
			(pintype "passive")
		)
		(pad "2" smd roundrect
			(at 0.48 0)
			(size 0.59 0.64)
			(layers "B.Cu" "B.Mask" "B.Paste")
			(roundrect_rratio 0.25)
			(net 827 "Net-(R253-Pad1)")
			(pintype "passive")
		)
	)
	(footprint "antmicro-footprints:C_0603_1608Metric"
		(layer "B.Cu")
		(at 188.5 145.75 -90)
		(descr "Capacitor SMD 0603")
		(tags "capacitor 0603")
		(property "Reference" "C44"
			(at -11.875 30.65 90)
			(layer "B.SilkS")
			(effects
				(font
					(size 0.7 0.7)
					(thickness 0.15)
				)
				(justify left bottom mirror)
			)
		)
		(property "Value" "C_47u_0603"
			(at -1.42757 -1.770288 90)
			(layer "B.Fab")
			(effects
				(font
					(size 0.7 0.7)
					(thickness 0.15)
				)
				(justify left bottom mirror)
			)
		)
		(property "Datasheet" "https://www.murata.com/products/productdetail?partno=GRM188R60J476ME15%23"
			(at 0 0 270)
			(layer "F.Fab")
			(hide yes)
			(effects
				(font
					(size 1.27 1.27)
					(thickness 0.15)
				)
			)
		)
		(property "Manufacturer" "Murata"
			(at 0 0 270)
			(unlocked yes)
			(layer "B.Fab")
			(hide yes)
			(effects
				(font
					(size 1 1)
					(thickness 0.15)
				)
				(justify mirror)
			)
		)
		(property "MPN" "GRM188R60J476ME15D"
			(at 0 0 270)
			(unlocked yes)
			(layer "B.Fab")
			(hide yes)
			(effects
				(font
					(size 1 1)
					(thickness 0.15)
				)
				(justify mirror)
			)
		)
		(property "Val" "47u"
			(at 0 0 270)
			(unlocked yes)
			(layer "B.Fab")
			(hide yes)
			(effects
				(font
					(size 1 1)
					(thickness 0.15)
				)
				(justify mirror)
			)
		)
		(property "License" "Apache-2.0"
			(at 0 0 270)
			(unlocked yes)
			(layer "B.Fab")
			(hide yes)
			(effects
				(font
					(size 1 1)
					(thickness 0.15)
				)
				(justify mirror)
			)
		)
		(property "Author" "Antmicro"
			(at 0 0 270)
			(unlocked yes)
			(layer "B.Fab")
			(hide yes)
			(effects
				(font
					(size 1 1)
					(thickness 0.15)
				)
				(justify mirror)
			)
		)
		(property "Voltage" ""
			(at 0 0 270)
			(unlocked yes)
			(layer "B.Fab")
			(hide yes)
			(effects
				(font
					(size 1 1)
					(thickness 0.15)
				)
				(justify mirror)
			)
		)
		(property "Dielectric" ""
			(at 0 0 270)
			(unlocked yes)
			(layer "B.Fab")
			(hide yes)
			(effects
				(font
					(size 1 1)
					(thickness 0.15)
				)
				(justify mirror)
			)
		)
		(sheetname "/FPGA power/")
		(sheetfile "fpga-power.kicad_sch")
		(attr smd)
		(fp_line
			(start -0.15 0.4)
			(end 0.15 0.4)
			(stroke
				(width 0.15)
				(type solid)
			)
			(layer "B.SilkS")
		)
		(fp_line
			(start -0.15 -0.4)
			(end 0.15 -0.4)
			(stroke
				(width 0.15)
				(type solid)
			)
			(layer "B.SilkS")
		)
		(fp_rect
			(start -1.25 0.65)
			(end 1.25 -0.65)
			(stroke
				(width 0.05)
				(type solid)
			)
			(fill no)
			(layer "B.CrtYd")
		)
		(fp_rect
			(start -0.8 0.4)
			(end 0.8 -0.4)
			(stroke
				(width 0.15)
				(type solid)
			)
			(fill no)
			(layer "B.Fab")
		)
		(fp_text user "${REFERENCE}"
			(at -1.682 -3.895 90)
			(layer "B.Fab")
			(effects
				(font
					(size 0.7 0.7)
					(thickness 0.15)
				)
				(justify left bottom mirror)
			)
		)
		(fp_text user "License: Apache-2.0"
			(at -1.682 -5.895 90)
			(layer "B.Fab")
			(effects
				(font
					(size 0.7 0.7)
					(thickness 0.15)
				)
				(justify left bottom mirror)
			)
		)
		(fp_text user "Author: Antmicro"
			(at -1.682 -4.894 90)
			(layer "B.Fab")
			(effects
				(font
					(size 0.7 0.7)
					(thickness 0.15)
				)
				(justify left bottom mirror)
			)
		)
		(pad "1" smd roundrect
			(at -0.7 0 270)
			(size 0.8 1)
			(layers "B.Cu" "B.Mask" "B.Paste")
			(roundrect_rratio 0.2)
			(net 687 "VDDQ")
			(pintype "passive")
		)
		(pad "2" smd roundrect
			(at 0.7 0 270)
			(size 0.8 1)
			(layers "B.Cu" "B.Mask" "B.Paste")
			(roundrect_rratio 0.2)
			(net 1 "GND")
			(pintype "passive")
		)
	)
	(footprint "antmicro-footprints:C_0402_1005Metric_EIA"
		(layer "B.Cu")
		(at 183 150.519 -90)
		(descr "Capacitor SMD 0402 (1005 Metric), square (rectangular) end terminal, IPC_7351 nominal, (Body size source: IPC-SM-782 page 76, https://www.pcb-3d.com/wordpress/wp-content/uploads/ipc-sm-782a_amendment_1_and_2.pdf)")
		(tags "capacitor 0402")
		(property "Reference" "C336"
			(at -12.219 30.6 90)
			(layer "B.SilkS")
			(effects
				(font
					(size 0.7 0.7)
					(thickness 0.15)
				)
				(justify left bottom mirror)
			)
		)
		(property "Value" "C_100n_0402"
			(at 0 -1.169 90)
			(layer "B.Fab")
			(effects
				(font
					(size 0.7 0.7)
					(thickness 0.15)
				)
				(justify left bottom mirror)
			)
		)
		(property "Manufacturer" "Murata"
			(at 0 0 270)
			(unlocked yes)
			(layer "B.Fab")
			(hide yes)
			(effects
				(font
					(size 1 1)
					(thickness 0.15)
				)
				(justify mirror)
			)
		)
		(property "MPN" "GRM155R61H104KE14D"
			(at 0 0 270)
			(unlocked yes)
			(layer "B.Fab")
			(hide yes)
			(effects
				(font
					(size 1 1)
					(thickness 0.15)
				)
				(justify mirror)
			)
		)
		(property "Val" "100n"
			(at 0 0 270)
			(unlocked yes)
			(layer "B.Fab")
			(hide yes)
			(effects
				(font
					(size 1 1)
					(thickness 0.15)
				)
				(justify mirror)
			)
		)
		(property "License" "Apache-2.0"
			(at 0 0 270)
			(unlocked yes)
			(layer "B.Fab")
			(hide yes)
			(effects
				(font
					(size 1 1)
					(thickness 0.15)
				)
				(justify mirror)
			)
		)
		(property "Author" "Antmicro"
			(at 0 0 270)
			(unlocked yes)
			(layer "B.Fab")
			(hide yes)
			(effects
				(font
					(size 1 1)
					(thickness 0.15)
				)
				(justify mirror)
			)
		)
		(property "Voltage" "50V"
			(at 0 0 270)
			(unlocked yes)
			(layer "B.Fab")
			(hide yes)
			(effects
				(font
					(size 1 1)
					(thickness 0.15)
				)
				(justify mirror)
			)
		)
		(property "Dielectric" "X5R"
			(at 0 0 270)
			(unlocked yes)
			(layer "B.Fab")
			(hide yes)
			(effects
				(font
					(size 1 1)
					(thickness 0.15)
				)
				(justify mirror)
			)
		)
		(sheetname "/FPGA banks HP/")
		(sheetfile "fpga-hp-banks.kicad_sch")
		(attr smd)
		(fp_rect
			(start -0.95 0.45)
			(end 0.95 -0.45)
			(stroke
				(width 0.05)
				(type default)
			)
			(fill no)
			(layer "B.CrtYd")
		)
		(fp_line
			(start -0.5 0.25)
			(end 0.498 0.25)
			(stroke
				(width 0.15)
				(type solid)
			)
			(layer "B.Fab")
		)
		(fp_line
			(start 0.498 0.25)
			(end 0.498 -0.248)
			(stroke
				(width 0.15)
				(type solid)
			)
			(layer "B.Fab")
		)
		(fp_line
			(start -0.5 -0.248)
			(end -0.5 0.25)
			(stroke
				(width 0.15)
				(type solid)
			)
			(layer "B.Fab")
		)
		(fp_line
			(start 0.498 -0.248)
			(end -0.5 -0.248)
			(stroke
				(width 0.15)
				(type solid)
			)
			(layer "B.Fab")
		)
		(fp_text user "${REFERENCE}"
			(at -0.9656 -3.169 90)
			(layer "B.Fab")
			(effects
				(font
					(size 0.7 0.7)
					(thickness 0.15)
				)
				(justify left bottom mirror)
			)
		)
		(fp_text user "License: Apache-2.0"
			(at -0.9656 -4.369 90)
			(layer "B.Fab")
			(effects
				(font
					(size 0.7 0.7)
					(thickness 0.15)
				)
				(justify left bottom mirror)
			)
		)
		(fp_text user "Author: Antmicro"
			(at -0.9656 -5.569 90)
			(layer "B.Fab")
			(effects
				(font
					(size 0.7 0.7)
					(thickness 0.15)
				)
				(justify left bottom mirror)
			)
		)
		(pad "1" smd roundrect
			(at -0.5 0 180)
			(size 0.6 0.6)
			(layers "B.Cu" "B.Mask" "B.Paste")
			(roundrect_rratio 0.25)
			(net 546 "/FPGA banks HP/VREF_67")
			(pintype "passive")
		)
		(pad "2" smd roundrect
			(at 0.498 0 270)
			(size 0.6 0.6)
			(layers "B.Cu" "B.Mask" "B.Paste")
			(roundrect_rratio 0.25)
			(net 1 "GND")
			(pintype "passive")
		)
	)
)
